# S9S_MB_2U (Grand Teton) — schematic parts with pin connectivity, parts 5983–5983 of 6093; source: Cadence DE-HDL packaged netlist (pstxprt.dat, pstxnet.dat, pstchip.dat)

U249  LCMXO3LF9400C5BG484C  LCMXO3LF-9400C-5BG484C IC  pkg BGA484_0-8_19X19_H67  page 216  (pins 1-329 of 484)
  A1  GND1  POWER  = GND
  A2  \pt9b||l_gpllc\  BI  = FM_GPU_PWR_EN
  A3  PT10B  BI  = FM_GPU_HSC_EN_R
  A4  PT11B  BI  = SMB_BMC_SWB_EN
  A5  PT12B  BI  = FM_TPM_PRSNT_R_N
  A6  PT13B  BI  = FM_PECI_MUX_SEL_N
  A7  PT14B  BI  = FM_OCP_SFF_PWR_GOOD_R
  A8  PT20B  BI  = IRQ_SML1_PMBUS_PLD_ALERT_N
  A9  PT21B  BI  = GPU_NVS_PWR_BRAKE_R_N
  A10  \pt23b||pclkc0_1\  BI  = SMB_HOST_3V3AUX_PLD_SCL
  A11  PT24B  BI  = GPU_WP_HW_CTRL_R_N
  A12  \pt27d||sda||pclkc0_0\  BI  = SMB_1_PLD_3V3AUX_SDA_R1
  A13  PT29A  BI  = PWRGD_PVNN_MAIN_CPU0
  A14  PT30A  BI  = PWRGD_PVPP_HBM_CPU1
  A15  PT38A  BI  = SGPIO_DEBUG_PLD_DOUT
  A16  PT39A  BI  = SGPIO_OCP_SFF_DATAOUT
  A17  PT40A  BI  = SGPIO_OCP_V3_2_DATAOUT
  A18  PT41A  BI  = GPU_FPGA_READY_ISO_R
  A19  PT42A  BI  = P12V_HSC_TEMP_ALERT_R_N
  A20  \pt43a||r_gpllt\  BI  = NC_FPGA_PT43A
  A21  \pt44a||r_gpllt\  BI  = NC_FPGA_PT44A
  A22  GND2  POWER  = GND
  AA1  PL29B  BI  = H_CPU_NMI_LVC1_R_N
  AA2  PB5A  BI  = FM_ADR_ACK_R
  AA3  \pb7a||csspin\  BI  = FM_ADR_MODE0_R
  AA4  PB8A  BI  = IRQ_PVCCD_CPU0_VRHOT_LVC3_N
  AA5  PB10A  BI  = PWRGD_PLT_AUX_CPU0_LVT3_R
  AA6  PB11A  BI  = RST_MB_STBY_R_N
  AA7  PB13A  BI  = FM_DIS_PS_PWROK_DLY
  AA8  PB18A  BI  = FM_CPU_RMCA_CATERR_LVT3_R_N
  AA9  PB19A  BI  = JTAG_DBP_BMC_PRDY_R_N
  AA10  \pb22a||pclkt2_0\  BI  = CLK_25M_OSC_MAIN_FPGA
  AA11  PB24A  BI  = PRSNT_CABLE_GPU_B3_ISO_R_N
  AA12  \pb29b||pclkc2_1\  BI  = IRQ_PSYS_CRIT_N
  AA13  PB30B  BI  = IRQ_PVCCD_CPU1_VRHOT_LVC3_N
  AA14  PB33B  BI  = FM_SYS_THROTTLE_R_N
  AA15  PB35B  BI  = NC_FPGA_PB35B
  AA16  PB38B  BI  = FM_PCH_PLD_GLB_RST_WARN_N
  AA17  PB40B  BI  = FM_BMC_READY_R_PLD_N
  AA18  PB41B  BI  = CLK_GPU_1_OE_N
  AA19  PB43B  BI  = FM_PLD_REV_N
  AA20  PB44B  BI  = HPDB_HSC_PWRGD_ISO_R
  AA21  \pb46b||si||sispi\  BI  = NC_FPGA_PB46B
  AA22  PR29A  BI  = LED_HDD_ACTIVITY_B_PLD_N
  AB1  GND51  POWER  = GND
  AB2  PB5B  BI  = FM_UV_ADR_TRIGGER_R_N
  AB3  PB7B  BI  = FM_ADR_MODE1_R
  AB4  PB8B  BI  = IRQ_BMC_PCH_NMI_R
  AB5  PB10B  BI  = PWRGD_PLT_AUX_CPU1_LVT3_R
  AB6  PB11B  BI  = RST_SMB_SWITCH_N
  AB7  PB13B  BI  = FM_PCH_CRASHLOG_TRIG_R_N
  AB8  PB18B  BI  = FM_PCH_BMC_THERMTRIP_N
  AB9  PB19B  BI  = FM_DEBUG_PORT_PRSNT_N
  AB10  \pb22b||pclkc2_0\  BI  = NC_FPGA_PB22B
  AB11  PB24B  BI  = GPU_3V3IO_RSVD3_FFU_ISO_R
  AB12  \pb29a||pclkt2_1\  BI  = IRQ_SGPIO_INTR_N_R
  AB13  PB30A  BI  = IRQ_TPM_SPI_N
  AB14  PB33A  BI  = RST_PLTRST_PLD_B_N
  AB15  PB35A  BI  = FM_SPD_REMOTE_EN_R
  AB16  PB38A  BI  = VIRTUAL_RESEAT
  AB17  PB40A  BI  = FM_PCHHOT_R_N
  AB18  PB41A  BI  = JTAG_DBP_BMC_PREQ_R_N
  AB19  PB43A  BI  = CLK_GEN2_BMC_RC_OE_N
  AB20  PB44A  BI  = HGX_DETECT_N_R
  AB21  \pb46a||sn\  BI  = PULL_FPGA_PB46A
  AB22  GND52  POWER  = GND
  B1  \pt9a||l_gpllt\  BI  = FM_SWB_PWR_EN
  B2  PT10A  BI  = FM_FAN_PWR_EN
  B3  PT11A  BI  = FM_SWB_BIC_READY_ISO_R_N
  B4  PT12A  BI  = FM_PCH_PRSNT_N
  B5  PT13A  BI  = IRQ_HSC_FAULT_R1_N
  B6  PT14A  BI  = FM_OCP_V3_2_PWR_GOOD_R
  B7  GND3  POWER  = GND
  B8  PT20A  BI  = IRQ_SML0_ALERT_R_N
  B9  PT21A  BI  = GPU_FPGA_THERM_OVERT_ISO_R_N
  B10  \pt23a||pclkt0_1\  BI  = SMB_HOST_3V3AUX_PLD_SDA
  B11  PT24A  BI  = GPU_FPGA_OVERT_ISO_R_N
  B12  \pt27c||scl||pclkt0_0\  BI  = SMB_1_PLD_3V3AUX_SCL_R1
  B13  PT29B  BI  = PWRGD_PVNN_PCH_AUX
  B14  PT30B  BI  = FM_NCSI_OCP_V3_2_R_OE
  B15  PT38B  BI  = SGPIO_DEBUG_PLD_CLK
  B16  GND4  POWER  = GND
  B17  PT39B  BI  = SGPIO_OCP_SFF_CLK
  B18  PT40B  BI  = SGPIO_OCP_V3_2_CLK
  B19  PT41B  BI  = PU_MAIN_FPGA_CONFIG_DONE
  B20  PT42B  BI  = P12V_HSC_T_CRIT_R_N
  B21  \pt43b||r_gpllc\  BI  = NC_FPGA_PT43B
  B22  \pt44b||r_gpllc\  BI  = NC_FPGA_PT44B
  C1  \pl4a||l_gpllt_in\  BI  = RST_PLD_CPU0_DRAM_AB_N
  C2  GND5  POWER  = GND
  C3  PT10C  BI  = BIC_MONITER_ISO_R
  C4  PT10D  BI  = BMC_MONITER
  C5  PT12D  BI  = FM_BMC_SUSACK_R_N
  C6  PT14C  BI  = FM_S3M_CPU0_CPLD_CRC_ERROR
  C7  VCCIO0_1  POWER  = P3V3_AUX_FPGA_VCCIO0
  C8  PT15A  BI  = OCP_SFF_CLK_OE_R_N
  C9  PT20C  BI  = FM_SLP_SUS_RSM_RST_N
  C10  \pt22d||tms\  BI  = JTAG_PLD_TMS_R
  C11  GND6  POWER  = GND
  C12  VCCIO0_2  POWER  = P3V3_AUX_FPGA_VCCIO0
  C13  PT29C  BI  = PWRGD_PVNN_MAIN_CPU1
  C14  PT30C  BI  = SGPIO_BMC_DOUT
  C15  PT38C  BI  = SGPIO_DEBUG_PLD_DIN
  C16  VCCIO0_3  POWER  = P3V3_AUX_FPGA_VCCIO0
  C17  PT39C  BI  = SGPIO_OCP_SFF_DATAIN
  C18  PT41C  BI  = JTAG_BMC_SW_PLD_OE
  C19  PT43C  BI  = NC_FPGA_PT43C
  C20  PT43D  BI  = NC_FPGA_PT43D
  C21  \pr2a||r_gpllt_fb\  BI  = FM_PVCCD_HV_CPU0_EN
  C22  \pr2b||r_gpllc_fb\  BI  = FM_PVCCD_HV_CPU1_EN
  D1  PL5A  BI  = RST_PLD_CPU1_DRAM_AB_N
  D2  \pl4b||l_gpllc_in\  BI  = RST_PLD_CPU0_DRAM_CD_N
  D3  PL2A  BI  = RST_CPU0_DRAM_AB_PLD_LVT3_N
  D4  PL2B  BI  = RST_CPU0_DRAM_CD_PLD_LVT3_N
  D5  PT12C  BI  = VIRTUAL_RESEAT_FPGA_R_N
  D6  PT13C  BI  = OCP_V3_2_AUX_PWR_PLD_EN
  D7  PT14D  BI  = FM_S3M_CPU1_CPLD_CRC_ERROR
  D8  PT15B  BI  = IRQ_SML1_PMBUS_BMC_ALERT_N
  D9  PT20D  BI  = PU_RST_DEDI_BUSY_PLD_N
  D10  \pt22c||tck\  BI  = JTAG_PLD_TCK_R
  D11  PT24D  BI  = GPU_FPGA_EROT_FATALERR_ISO_R_N
  D12  PT27A  BI  = PWRGD_P5V_AUX_R2
  D13  PT29D  BI  = PWRGD_PVPP_HBM_CPU0
  D14  PT30D  BI  = SGPIO_BMC_CLK
  D15  PT38D  BI  = SGPIO_DEBUG_PLD_LD_N
  D16  PT39D  BI  = SGPIO_OCP_SFF_LD_N
  D17  PT40D  BI  = SGPIO_OCP_V3_2_LD_N
  D18  PT41D  BI  = NC_FPGA_PT41D
  D19  PR3C  BI  = FM_PVCCINFAON_CPU0_R_EN
  D20  PR3D  BI  = FM_PVCCINFAON_CPU1_R_EN
  D21  \pr3b||r_gpllc_in\  BI  = FM_PVCCFA_EHV_FIVRA_CPU1_R_EN
  D22  \pr3a||r_gpllt_in\  BI  = FM_PVCCFA_EHV_FIVRA_CPU0_R_EN
  E1  PL6A  BI  = NC
  E2  PL5B  BI  = RST_PLD_CPU1_DRAM_CD_N
  E3  PL5C  BI  = RST_PLD_CPU1_DRAM_EF_N
  E4  \pl3a||l_gpllt_fb\  BI  = RST_CPU1_DRAM_AB_PLD_LVT3_N
  E5  GND7  POWER  = GND
  E6  PT9C  BI  = FM_SWB_PWRGD_ISO_R
  E7  PT13D  BI  = OCP_SFF_AUX_PWR_PLD_EN
  E8  \pt15c||tdo\  BI  = JTAG_PLD_TDO_R
  E9  \pt15d||tdi\  BI  = JTAG_PLD_TDI_R
  E10  PT22B  BI  = GPU_HMC_PRSNT_ISO_R_N
  E11  PT24C  BI  = GPU_PRSNT_N_ISO_R
  E12  PT27B  BI  = PWRGD_P3V3
  E13  PT28C  BI  = PWRGD_PVCCFA_EHV_FIVRA_CPU0
  E14  \pt31c||jtagenb\  BI  = JTAG_PLD_JTAGEN
  E15  \pt31d||programn\  BI  = PU_FPGA_D12_PROGRAMN
  E16  PT40C  BI  = SGPIO_OCP_V3_2_DATAIN
  E17  \pt44d||done\  BI  = NC_FPGA_PT44D
  E18  GND8  POWER  = GND
  E19  PR4C  BI  = FM_PVCCIN_CPU0_R_EN
  E20  PR4D  BI  = FM_PVCCIN_CPU1_R_EN
  E21  PR4B  BI  = FM_PVNN_MAIN_CPU1_EN
  E22  PR4A  BI  = FM_PVNN_MAIN_CPU0_EN
  F1  PL6B  BI  = NC
  F2  GND9  POWER  = GND
  F3  VCCIO5_1  POWER  = P3V3_AUX_FPGA_VCCIO5
  F4  PL5D  BI  = RST_PLD_CPU1_DRAM_GH_N
  F5  \pl3b||l_gpllc_fb\  BI  = RST_CPU1_DRAM_CD_PLD_LVT3_N
  F6  PL2C  BI  = RST_CPU0_DRAM_EF_PLD_LVT3_N
  F7  PT9D  BI  = FM_GPU_PWRGD_ISO_R
  F8  PT11C  BI  = RST_BMC_FROM_SWB_ISO_R_N
  F9  PT21C  BI  = GPU_FPGA_EROT_RST_R_N
  F10  PT22A  BI  = GPU_BASE_HMC_READY_ISO_R
  F11  PT23D  BI  = GPU_FPGA_EROT_RECOV_R_N
  F12  PT28B  BI  = PWRGD_PVCCD_HV_CPU0
  F13  PT28D  BI  = PWRGD_PVCCIN_CPU0
  F14  PT31B  BI  = SGPIO_BMC_LD_N
  F15  PT42C  BI  = RST_SRST_PLD_BMC_R_N
  F16  \pt44c||initn\  BI  = NC_FPGA_PT44C
  F17  PR2C  BI  = FM_PVCCFA_EHV_CPU0_R_EN
  F18  PR5C  BI  = FM_AUX_SW_EN
  F19  PR5D  BI  = FM_PCH_P1V8_AUX_EN
  F20  VCCIO1_1  POWER  = P3V3_AUX_FPGA_VCCIO1
  F21  GND10  POWER  = GND
  F22  PR5A  BI  = FM_PVPP_HBM_CPU1_EN
  G1  \pl7b||pclkc5_0\  BI  = PWRGD_DRAMPWRGD_CPU0_CD_R_LVC1
  G2  \pl7a||pclkt5_0\  BI  = PWRGD_DRAMPWRGD_CPU0_AB_R_LVC1
  G3  PL6C  BI  = NC
  G4  PL6D  BI  = NC
  G5  PL4C  BI  = RST_PLD_CPU0_DRAM_EF_N
  G6  PL3C  BI  = RST_CPU1_DRAM_EF_PLD_LVT3_N
  G7  PL2D  BI  = RST_CPU0_DRAM_GH_PLD_LVT3_N
  G8  PT11D  BI  = SMB_BMC_GPU_EN
  G9  PT21D  BI  = GPU_BASE_STBY_EN_R
  G10  VCCIO0_4  POWER  = P3V3_AUX_FPGA_VCCIO0
  G11  PT23C  BI  = GPU_FPGA_BOOT_EN_R
  G12  PT28A  BI  = PWRGD_P3V3_AUX_PLD
  G13  VCCIO0_5  POWER  = P3V3_AUX_FPGA_VCCIO0
  G14  PT31A  BI  = SGPIO_BMC_DIN_R
  G15  PT42D  BI  = NC_FPGA_PT42D
  G16  PR2D  BI  = FM_PVCCFA_EHV_CPU1_R_EN
  G17  PR7C  BI  = PWRGD_PVCCINFAON_CPU0
  G18  PR6D  BI  = PWRGD_PVCCIN_CPU1
  G19  PR6C  BI  = FM_ESPI_PLD_R_EN
  G20  PR6B  BI  = FM_P1V05_PCH_AUX_EN
  G21  PR6A  BI  = FM_P5V_EN
  G22  PR5B  BI  = FM_PVPP_HBM_CPU0_EN
  H1  PL10B  BI  = PWRGD_DRAMPWRGD_CPU1_CD_R_LVC1
  H2  PL10A  BI  = PWRGD_DRAMPWRGD_CPU1_AB_R_LVC1
  H3  PL7D  BI  = PWRGD_DRAMPWRGD_CPU0_GH_R_LVC1
  H4  PL7C  BI  = PWRGD_DRAMPWRGD_CPU0_EF_R_LVC1
  H5  PL11A  BI  = FM_BOARD_BMC_SKU_ID4
  H6  PL4D  BI  = RST_PLD_CPU0_DRAM_GH_N
  H7  PL3D  BI  = RST_CPU1_DRAM_GH_PLD_LVT3_N
  H8  GND11  POWER  = GND
  H9  VCCIO0_6  POWER  = P3V3_AUX_FPGA_VCCIO0
  H10  GND12  POWER  = GND
  H11  VCCIO0_7  POWER  = P3V3_AUX_FPGA_VCCIO0
  H12  VCCIO0_8  POWER  = P3V3_AUX_FPGA_VCCIO0
  H13  GND13  POWER  = GND
  H14  VCCIO0_9  POWER  = P3V3_AUX_FPGA_VCCIO0
  H15  GND14  POWER  = GND
  H16  PR10D  BI  = PWRGD_PS_PWROK_PLD_ISO_R
  H17  PR10C  BI  = FM_PFR_DSW_PWROK_N
  H18  PR10B  BI  = PWRGD_PVCCD_HV_CPU1
  H19  PR10A  BI  = PWRGD_PVCCFA_EHV_FIVRA_CPU1
  H20  PR7D  BI  = PWRGD_PVCCINFAON_CPU1
  H21  PR7B  BI  = PWRGD_PVCCFA_EHV_CPU1
  H22  PR7A  BI  = PWRGD_PVCCFA_EHV_CPU0
  J1  PL12B  BI  = FAB_BMC_REV_ID2
  J2  PL12A  BI  = FM_BOARD_BMC_SKU_ID0
  J3  PL11D  BI  = FM_BOARD_BMC_SKU_ID1
  J4  PL11C  BI  = FM_BOARD_BMC_SKU_ID2
  J5  PL11B  BI  = FM_BOARD_BMC_SKU_ID3
  J6  PL10D  BI  = PWRGD_DRAMPWRGD_CPU1_GH_R_LVC1
  J7  PL10C  BI  = PWRGD_DRAMPWRGD_CPU1_EF_R_LVC1
  J8  VCCIO5_2  POWER  = P3V3_AUX_FPGA_VCCIO5
  J9  GND15  POWER  = GND
  J10  GND16  POWER  = GND
  J11  GND17  POWER  = GND
  J12  GND18  POWER  = GND
  J13  GND19  POWER  = GND
  J14  GND20  POWER  = GND
  J15  VCCIO1_2  POWER  = P3V3_AUX_FPGA_VCCIO1
  J16  PR11A  BI  = PWRGD_P1V05_PCH_AUX
  J17  PR11B  BI  = PWRGD_P1V8_PCH_AUX_PLD
  J18  PR11C  BI  = PWRGD_SYS_PWROK_R
  J19  PR11D  BI  = PWRGD_PCH_PWROK_R
  J20  PR12C  BI  = E1S_0_P3V3_ADC_ALERT
  J21  PR12A  BI  = IRQ_PVCCFA_CPU0_VRHOT_R_N
  J22  PR12B  BI  = IRQ_PVCCFA_CPU1_VRHOT_R_N
  K1  PL14B  BI  = HP_E1S_0_P3V3_PWRGD_PLD
  K2  PL14A  BI  = HP_LVC3_E1S_0_HSC_PWRGD_PLD
  K3  PL13D  BI  = HP_LVC3_OCP_V3_2_PRSNT2_PLD_N
  K4  PL13C  BI  = HP_LVC3_OCP_V3_1_PRSNT2_PLD_N
  K5  PL13B  BI  = HP_LVC3_OCP_V3_2_FUSE_PWRGD
  K6  PL12D  BI  = FAB_BMC_REV_ID0
  K7  PL12C  BI  = FAB_BMC_REV_ID1
  K8  VCCIO5_3  POWER  = P3V3_AUX_FPGA_VCCIO5
  K9  GND21  POWER  = GND
  K10  VCC1  POWER  = VCC_PLD_CORE
  K11  VCC2  POWER  = VCC_PLD_CORE
  K12  VCC3  POWER  = VCC_PLD_CORE
  K13  VCC4  POWER  = VCC_PLD_CORE
  K14  GND22  POWER  = GND
  K15  VCCIO1_3  POWER  = P3V3_AUX_FPGA_VCCIO1
  K16  PR13D  BI  = P12V_SCM_ADC_ALERT
  K17  PR13C  BI  = M2_0_P3V3_ADC_ALERT
  K18  PR13B  BI  = OCP_V3_2_P3V3_ADC_ALERT
  K19  PR13A  BI  = NC_FPGA_PR13A
  K20  PR12D  BI  = OCP_SFF_P3V3_ADC_ALERT
  K21  GND23  POWER  = GND
  K22  PR16A  BI  = FM_SOL_UART_CH_SEL
  L1  \pl16a||pclkt4_0\  BI  = NC
  L2  GND24  POWER  = GND
  L3  PL16C  BI  = NC
  L4  PL16D  BI  = NC
  L5  PL14D  BI  = HP_LVC3_SCM_HSC_PWRGD_PLD
  L6  PL14C  BI  = E1S_0_CLK_OE_N
  L7  PL13A  BI  = HP_LVC3_OCP_V3_1_FUSE_PWRGD
  L8  VCCIO4_1  POWER  = P3V3_AUX_FPGA_VCCIO4
  L9  GND25  POWER  = GND
  L10  GND26  POWER  = GND
  L11  VCC5  POWER  = VCC_PLD_CORE
  L12  VCC6  POWER  = VCC_PLD_CORE
  L13  GND27  POWER  = GND
  L14  GND28  POWER  = GND
  L15  VCCIO1_4  POWER  = P3V3_AUX_FPGA_VCCIO1
  L16  PR14B  BI  = NC_FPGA_PR14B
  L17  PR14A  BI  = NC_FPGA_PR14A
  L18  GND29  POWER  = GND
  L19  PR14C  BI  = FM_UARTSW_LSB_N
  L20  PR14D  BI  = FM_UARTSW_MSB_N
  L21  PR16B  BI  = FM_THERMAL_ALERT_R_N
  L22  PR16C  BI  = NC_FPGA_PR16C
  M1  PL17A  BI  = NC
  M2  \pl16b||pclkc4_0\  BI  = NC
  M3  VCCIO4_3  POWER  = P3V3_AUX_FPGA_VCCIO4
  M4  GND30  POWER  = GND
  M5  PL17D  BI  = NC
  M6  PL17C  BI  = NC
  M7  PL19D  BI  = NC
  M8  VCCIO4_2  POWER  = P3V3_AUX_FPGA_VCCIO4
  M9  GND31  POWER  = GND
  M10  GND32  POWER  = GND
  M11  VCC7  POWER  = VCC_PLD_CORE
  M12  VCC8  POWER  = VCC_PLD_CORE
  M13  GND33  POWER  = GND
  M14  GND34  POWER  = GND
  M15  VCCIO1_5  POWER  = P3V3_AUX_FPGA_VCCIO1
  M16  PR18A  BI  = FM_CPU0_SKTOCC_LVT3_PLD_N
  M17  PR16D  BI  = NC_FPGA_PR16D
  M18  VCCIO1_6  POWER  = P3V3_AUX_FPGA_VCCIO1
  M19  PR17D  BI  = RST_PCIE_CPU1_DEV_PERST_N
  M20  PR17C  BI  = RST_PCIE_CPU0_DEV_PERST_N
  M21  \pr17b||pclkc1_0\  BI  = SMB_2_PLD_3V3AUX_SDA_R1
  M22  \pr17a||pclkt1_0\  BI  = SMB_2_PLD_3V3AUX_SCL_R1
  N1  PL17B  BI  = NC
  N2  PL18A  BI  = NC
  N3  PL18C  BI  = NC
  N4  PL18D  BI  = NC
  N5  PL20B  BI  = NC
  N6  PL20C  BI  = NC
  N7  PL20D  BI  = NC
  N8  VCCIO3_1  POWER  = P3V3_AUX_FPGA_VCCIO3
  N9  GND35  POWER  = GND
  N10  VCC9  POWER  = VCC_PLD_CORE
  N11  VCC10  POWER  = VCC_PLD_CORE
  N12  VCC11  POWER  = VCC_PLD_CORE
  N13  VCC12  POWER  = VCC_PLD_CORE
  N14  GND36  POWER  = GND
  N15  VCCIO1_7  POWER  = P3V3_AUX_FPGA_VCCIO1
  N16  PR18B  BI  = FM_CPU1_SKTOCC_LVT3_PLD_N
  N17  PR18C  BI  = FM_CPU0_PROC_ID0
  N18  PR18D  BI  = FM_CPU0_PROC_ID1
  N19  PR19D  BI  = FM_CPU0_PKGID1
  N20  PR19C  BI  = FM_CPU0_PKGID0
  N21  GND37  POWER  = GND
